(kicad_pcb
	(version 20260206)
	(generator "pcbnew")
	(generator_version "10.0")
	(general
		(thickness 1.6)
		(legacy_teardrops no)
	)
	(paper "A4")
	(title_block
		(title "01162023_DA0F0TEBIF0_F0T_Expander_BD_F_brd_V02_OCP.brd")
		(comment 1 "Grand Teton / footprints 5760-5765 of 9728")
	)
	(layers
		(0 "F.Cu" signal "TOP")
		(4 "In1.Cu" signal "GND")
		(6 "In2.Cu" signal "VCC")
		(8 "In3.Cu" signal "VCC1")
		(10 "In4.Cu" signal "GND1")
		(12 "In5.Cu" signal "IN1")
		(14 "In6.Cu" signal "GND2")
		(16 "In7.Cu" signal "IN2")
		(18 "In8.Cu" signal "GND3")
		(20 "In9.Cu" signal "IN3")
		(22 "In10.Cu" signal "GND4")
		(24 "In11.Cu" signal "IN4")
		(26 "In12.Cu" signal "GND5")
		(28 "In13.Cu" signal "IN5")
		(30 "In14.Cu" signal "GND6")
		(32 "In15.Cu" signal "IN6")
		(34 "In16.Cu" signal "GND7")
		(2 "B.Cu" signal "BOTTOM")
		(9 "F.Adhes" user "F.Adhesive")
		(11 "B.Adhes" user "B.Adhesive")
		(13 "F.Paste" user "Package Geometry/Pastemask Top")
		(15 "B.Paste" user "Package Geometry/Pastemask Bottom")
		(5 "F.SilkS" user "Ref Des/Silkscreen Top")
		(7 "B.SilkS" user "Ref Des/Silkscreen Bottom")
		(1 "F.Mask" user "Board Geometry/Soldermask Top")
		(3 "B.Mask" user "Board Geometry/Soldermask Bottom")
		(17 "Dwgs.User" user "User.Drawings")
		(19 "Cmts.User" user "User.Comments")
		(21 "Eco1.User" user "User.Eco1")
		(23 "Eco2.User" user "User.Eco2")
		(25 "Edge.Cuts" user "Board Geometry/Outline")
		(27 "Margin" user)
		(31 "F.CrtYd" user "Package Geometry/Place Bound Top")
		(29 "B.CrtYd" user "Package Geometry/Place Bound Bottom")
		(35 "F.Fab" user "Ref Des/Assembly Top")
		(33 "B.Fab" user "Ref Des/Assembly Bottom")
	)
	(footprint ""
		(layer "F.Cu")
		(at 38.7604 -96.1644)
		(property "Reference" "R42"
			(at 0 0 0)
			(layer "F.SilkS")
			(hide yes)
			(effects
				(font
					(size 1.27 1.27)
				)
			)
		)
		(property "Value" ""
			(at 0 0 0)
			(layer "F.Fab")
			(effects
				(font
					(size 1.27 1.27)
				)
			)
		)
		(duplicate_pad_numbers_are_jumpers no)
		(fp_line
			(start -0.7874 -0.4064)
			(end 0.7874 -0.4064)
			(stroke
				(width 0.1524)
				(type default)
			)
			(layer "F.SilkS")
		)
		(fp_line
			(start -0.7874 0.4064)
			(end -0.7874 -0.4064)
			(stroke
				(width 0.1524)
				(type default)
			)
			(layer "F.SilkS")
		)
		(fp_line
			(start 0.7874 -0.4064)
			(end 0.7874 0.4064)
			(stroke
				(width 0.1524)
				(type default)
			)
			(layer "F.SilkS")
		)
		(fp_line
			(start 0.7874 0.4064)
			(end -0.7874 0.4064)
			(stroke
				(width 0.1524)
				(type default)
			)
			(layer "F.SilkS")
		)
		(fp_line
			(start -0.67945 -0.305054)
			(end -0.12065 -0.305054)
			(stroke
				(width 0.1)
				(type default)
			)
			(layer "F.Fab")
		)
		(fp_line
			(start -0.67945 0.3048)
			(end -0.67945 -0.305054)
			(stroke
				(width 0.1)
				(type default)
			)
			(layer "F.Fab")
		)
		(fp_line
			(start -0.12065 -0.305054)
			(end -0.12065 -0.2794)
			(stroke
				(width 0.1)
				(type default)
			)
			(layer "F.Fab")
		)
		(fp_line
			(start -0.12065 -0.2794)
			(end 0.12065 -0.2794)
			(stroke
				(width 0.1)
				(type default)
			)
			(layer "F.Fab")
		)
		(fp_line
			(start -0.12065 0.2794)
			(end -0.12065 0.3048)
			(stroke
				(width 0.1)
				(type default)
			)
			(layer "F.Fab")
		)
		(fp_line
			(start -0.12065 0.3048)
			(end -0.67945 0.3048)
			(stroke
				(width 0.1)
				(type default)
			)
			(layer "F.Fab")
		)
		(fp_line
			(start 0.120396 0.2794)
			(end -0.12065 0.2794)
			(stroke
				(width 0.1)
				(type default)
			)
			(layer "F.Fab")
		)
		(fp_line
			(start 0.120396 0.3048)
			(end 0.120396 0.2794)
			(stroke
				(width 0.1)
				(type default)
			)
			(layer "F.Fab")
		)
		(fp_line
			(start 0.12065 -0.3048)
			(end 0.67945 -0.3048)
			(stroke
				(width 0.1)
				(type default)
			)
			(layer "F.Fab")
		)
		(fp_line
			(start 0.12065 -0.2794)
			(end 0.12065 -0.3048)
			(stroke
				(width 0.1)
				(type default)
			)
			(layer "F.Fab")
		)
		(fp_line
			(start 0.67945 -0.3048)
			(end 0.67945 0.3048)
			(stroke
				(width 0.1)
				(type default)
			)
			(layer "F.Fab")
		)
		(fp_line
			(start 0.67945 0.3048)
			(end 0.120396 0.3048)
			(stroke
				(width 0.1)
				(type default)
			)
			(layer "F.Fab")
		)
		(pad "1" smd circle
			(at -0.40005 0)
			(size 0 0)
			(layers "F.Cu" "F.Mask" "F.Paste")
			(net "PRSNT_NIC0_N")
		)
		(pad "2" smd circle
			(at 0.40005 0)
			(size 0 0)
			(layers "F.Cu" "F.Mask" "F.Paste")
			(net "PRSNTB3_NIC0_N")
		)
	)
	(footprint ""
		(layer "F.Cu")
		(at 378.453396 -297.791632)
		(property "Reference" "L136"
			(at 0 0 0)
			(layer "F.SilkS")
			(hide yes)
			(effects
				(font
					(size 1.27 1.27)
				)
			)
		)
		(property "Value" ""
			(at 0 0 0)
			(layer "F.Fab")
			(effects
				(font
					(size 1.27 1.27)
				)
			)
		)
		(duplicate_pad_numbers_are_jumpers no)
		(fp_line
			(start -1.63576 -0.8128)
			(end -1.63576 0.8128)
			(stroke
				(width 0.1524)
				(type default)
			)
			(layer "F.SilkS")
		)
		(fp_line
			(start -1.63576 -0.8128)
			(end 1.63576 -0.8128)
			(stroke
				(width 0.1524)
				(type default)
			)
			(layer "F.SilkS")
		)
		(fp_line
			(start 1.63576 -0.8128)
			(end 1.63576 0.8128)
			(stroke
				(width 0.1524)
				(type default)
			)
			(layer "F.SilkS")
		)
		(fp_line
			(start 1.63576 0.8128)
			(end -1.63576 0.8128)
			(stroke
				(width 0.1524)
				(type default)
			)
			(layer "F.SilkS")
		)
		(fp_line
			(start -1.56083 -0.738632)
			(end -1.56083 0.7366)
			(stroke
				(width 0.1)
				(type default)
			)
			(layer "F.Fab")
		)
		(fp_line
			(start -1.56083 0.7366)
			(end -1.524 0.7366)
			(stroke
				(width 0.1)
				(type default)
			)
			(layer "F.Fab")
		)
		(fp_line
			(start -1.524 0.7366)
			(end 1.524 0.7366)
			(stroke
				(width 0.1)
				(type default)
			)
			(layer "F.Fab")
		)
		(fp_line
			(start 1.524 0.7366)
			(end 1.560576 0.7366)
			(stroke
				(width 0.1)
				(type default)
			)
			(layer "F.Fab")
		)
		(fp_line
			(start 1.560576 -0.738632)
			(end -1.56083 -0.738632)
			(stroke
				(width 0.1)
				(type default)
			)
			(layer "F.Fab")
		)
		(fp_line
			(start 1.560576 0.7366)
			(end 1.560576 -0.738632)
			(stroke
				(width 0.1)
				(type default)
			)
			(layer "F.Fab")
		)
		(pad "1" smd rect
			(at -0.94996 0 180)
			(size 1.1176 1.3716)
			(layers "F.Cu" "F.Mask" "F.Paste")
			(net "P1V8_PLL0_PEX3")
		)
		(pad "2" smd rect
			(at 0.94996 0 180)
			(size 1.1176 1.3716)
			(layers "F.Cu" "F.Mask" "F.Paste")
			(net "PCEPLL0_VDDA18_PEX3")
		)
	)
	(footprint ""
		(layer "F.Cu")
		(at 140.074142 -173.865286 180)
		(property "Reference" "R1098"
			(at 0 0 180)
			(layer "F.SilkS")
			(hide yes)
			(effects
				(font
					(size 1.27 1.27)
				)
			)
		)
		(property "Value" ""
			(at 0 0 180)
			(layer "F.Fab")
			(effects
				(font
					(size 1.27 1.27)
				)
			)
		)
		(duplicate_pad_numbers_are_jumpers no)
		(fp_line
			(start -0.7874 -0.4064)
			(end 0.7874 -0.4064)
			(stroke
				(width 0.1524)
				(type default)
			)
			(layer "F.SilkS")
		)
		(fp_line
			(start 0.67945 0.3048)
			(end 0.120396 0.3048)
			(stroke
				(width 0.1)
				(type default)
			)
			(layer "F.Fab")
		)
		(fp_line
			(start 0.67945 -0.3048)
			(end 0.67945 0.3048)
			(stroke
				(width 0.1)
				(type default)
			)
			(layer "F.Fab")
		)
		(fp_line
			(start 0.12065 -0.2794)
			(end 0.12065 -0.3048)
			(stroke
				(width 0.1)
				(type default)
			)
			(layer "F.Fab")
		)
		(fp_line
			(start 0.12065 -0.3048)
			(end 0.67945 -0.3048)
			(stroke
				(width 0.1)
				(type default)
			)
			(layer "F.Fab")
		)
		(fp_line
			(start 0.120396 0.3048)
			(end 0.120396 0.2794)
			(stroke
				(width 0.1)
				(type default)
			)
			(layer "F.Fab")
		)
		(fp_line
			(start 0.120396 0.2794)
			(end -0.12065 0.2794)
			(stroke
				(width 0.1)
				(type default)
			)
			(layer "F.Fab")
		)
		(fp_line
			(start -0.12065 0.3048)
			(end -0.67945 0.3048)
			(stroke
				(width 0.1)
				(type default)
			)
			(layer "F.Fab")
		)
		(fp_line
			(start -0.12065 0.2794)
			(end -0.12065 0.3048)
			(stroke
				(width 0.1)
				(type default)
			)
			(layer "F.Fab")
		)
		(fp_line
			(start -0.12065 -0.2794)
			(end 0.12065 -0.2794)
			(stroke
				(width 0.1)
				(type default)
			)
			(layer "F.Fab")
		)
		(fp_line
			(start -0.12065 -0.305054)
			(end -0.12065 -0.2794)
			(stroke
				(width 0.1)
				(type default)
			)
			(layer "F.Fab")
		)
		(fp_line
			(start -0.67945 0.3048)
			(end -0.67945 -0.305054)
			(stroke
				(width 0.1)
				(type default)
			)
			(layer "F.Fab")
		)
		(fp_line
			(start -0.67945 -0.305054)
			(end -0.12065 -0.305054)
			(stroke
				(width 0.1)
				(type default)
			)
			(layer "F.Fab")
		)
		(pad "1" smd circle
			(at -0.40005 0 180)
			(size 0 0)
			(layers "F.Cu" "F.Mask" "F.Paste")
			(net "CLK_100M_DB2000QL_NIC2_R_DP")
		)
		(pad "2" smd circle
			(at 0.40005 0 180)
			(size 0 0)
			(layers "F.Cu" "F.Mask" "F.Paste")
			(net "CLK_100M_DB2000QL_NIC2_DP")
		)
	)
	(footprint ""
		(layer "F.Cu")
		(at 36.534344 -252.356874 -90)
		(property "Reference" "R1199"
			(at 0 0 270)
			(layer "F.SilkS")
			(hide yes)
			(effects
				(font
					(size 1.27 1.27)
				)
			)
		)
		(property "Value" ""
			(at 0 0 270)
			(layer "F.Fab")
			(effects
				(font
					(size 1.27 1.27)
				)
			)
		)
		(duplicate_pad_numbers_are_jumpers no)
		(fp_line
			(start -0.7874 0.4064)
			(end -0.7874 -0.4064)
			(stroke
				(width 0.1524)
				(type default)
			)
			(layer "F.SilkS")
		)
		(fp_line
			(start 0.7874 0.4064)
			(end -0.7874 0.4064)
			(stroke
				(width 0.1524)
				(type default)
			)
			(layer "F.SilkS")
		)
		(fp_line
			(start -0.7874 -0.4064)
			(end 0.7874 -0.4064)
			(stroke
				(width 0.1524)
				(type default)
			)
			(layer "F.SilkS")
		)
		(fp_line
			(start 0.7874 -0.4064)
			(end 0.7874 0.4064)
			(stroke
				(width 0.1524)
				(type default)
			)
			(layer "F.SilkS")
		)
		(fp_line
			(start -0.67945 0.3048)
			(end -0.67945 -0.305054)
			(stroke
				(width 0.1)
				(type default)
			)
			(layer "F.Fab")
		)
		(fp_line
			(start -0.12065 0.3048)
			(end -0.67945 0.3048)
			(stroke
				(width 0.1)
				(type default)
			)
			(layer "F.Fab")
		)
		(fp_line
			(start 0.120396 0.3048)
			(end 0.120396 0.2794)
			(stroke
				(width 0.1)
				(type default)
			)
			(layer "F.Fab")
		)
		(fp_line
			(start 0.67945 0.3048)
			(end 0.120396 0.3048)
			(stroke
				(width 0.1)
				(type default)
			)
			(layer "F.Fab")
		)
		(fp_line
			(start -0.12065 0.2794)
			(end -0.12065 0.3048)
			(stroke
				(width 0.1)
				(type default)
			)
			(layer "F.Fab")
		)
		(fp_line
			(start 0.120396 0.2794)
			(end -0.12065 0.2794)
			(stroke
				(width 0.1)
				(type default)
			)
			(layer "F.Fab")
		)
		(fp_line
			(start -0.12065 -0.2794)
			(end 0.12065 -0.2794)
			(stroke
				(width 0.1)
				(type default)
			)
			(layer "F.Fab")
		)
		(fp_line
			(start 0.12065 -0.2794)
			(end 0.12065 -0.3048)
			(stroke
				(width 0.1)
				(type default)
			)
			(layer "F.Fab")
		)
		(fp_line
			(start 0.12065 -0.3048)
			(end 0.67945 -0.3048)
			(stroke
				(width 0.1)
				(type default)
			)
			(layer "F.Fab")
		)
		(fp_line
			(start 0.67945 -0.3048)
			(end 0.67945 0.3048)
			(stroke
				(width 0.1)
				(type default)
			)
			(layer "F.Fab")
		)
		(fp_line
			(start -0.67945 -0.305054)
			(end -0.12065 -0.305054)
			(stroke
				(width 0.1)
				(type default)
			)
			(layer "F.Fab")
		)
		(fp_line
			(start -0.12065 -0.305054)
			(end -0.12065 -0.2794)
			(stroke
				(width 0.1)
				(type default)
			)
			(layer "F.Fab")
		)
		(pad "1" smd circle
			(at -0.40005 0 270)
			(size 0 0)
			(layers "F.Cu" "F.Mask" "F.Paste")
			(net "GND")
		)
		(pad "2" smd circle
			(at 0.40005 0 270)
			(size 0 0)
			(layers "F.Cu" "F.Mask" "F.Paste")
			(net "PEX0_MODE_SEL6")
		)
	)
	(footprint ""
		(layer "F.Cu")
		(at 3.198876 -30.549342 90)
		(property "Reference" "U126"
			(at -1.116076 -2.063496 90)
			(unlocked yes)
			(layer "F.SilkS")
			(effects
				(font
					(size 0.7874 0.5842)
					(thickness 0.1524)
				)
				(justify left)
			)
		)
		(property "Value" ""
			(at 0 0 90)
			(layer "F.Fab")
			(effects
				(font
					(size 1.27 1.27)
				)
			)
		)
		(duplicate_pad_numbers_are_jumpers no)
		(fp_line
			(start 1.463548 -1.549908)
			(end 1.463548 1.549908)
			(stroke
				(width 0.1524)
				(type default)
			)
			(layer "F.SilkS")
		)
		(fp_line
			(start 0.762 -1.549908)
			(end 1.463548 -1.549908)
			(stroke
				(width 0.1524)
				(type default)
			)
			(layer "F.SilkS")
		)
		(fp_line
			(start -0.787908 -1.549908)
			(end 0 -0.762)
			(stroke
				(width 0.1524)
				(type default)
			)
			(layer "F.SilkS")
		)
		(fp_line
			(start -1.463548 -1.549908)
			(end -0.787908 -1.549908)
			(stroke
				(width 0.1524)
				(type default)
			)
			(layer "F.SilkS")
		)
		(fp_line
			(start 0 -0.762)
			(end 0.762 -1.549908)
			(stroke
				(width 0.1524)
				(type default)
			)
			(layer "F.SilkS")
		)
		(fp_line
			(start 1.463548 1.549908)
			(end -1.463548 1.549908)
			(stroke
				(width 0.1524)
				(type default)
			)
			(layer "F.SilkS")
		)
		(fp_line
			(start -1.463548 1.549908)
			(end -1.463548 -1.549908)
			(stroke
				(width 0.1524)
				(type default)
			)
			(layer "F.SilkS")
		)
		(fp_poly
			(pts
				(xy -3.03022 -2.050288) (xy -2.811272 -1.392936) (xy -3.468624 -1.612138)
			)
			(stroke
				(width 0)
				(type default)
			)
			(fill yes)
			(layer "F.SilkS")
		)
		(fp_line
			(start 1.549908 -1.549908)
			(end 1.549908 1.549908)
			(stroke
				(width 0.1)
				(type default)
			)
			(layer "F.Fab")
		)
		(fp_line
			(start -1.549908 -1.549908)
			(end 1.549908 -1.549908)
			(stroke
				(width 0.1)
				(type default)
			)
			(layer "F.Fab")
		)
		(fp_line
			(start 1.549908 1.549908)
			(end -1.549908 1.549908)
			(stroke
				(width 0.1)
				(type default)
			)
			(layer "F.Fab")
		)
		(fp_line
			(start -1.549908 1.549908)
			(end -1.549908 -1.549908)
			(stroke
				(width 0.1)
				(type default)
			)
			(layer "F.Fab")
		)
		(fp_poly
			(pts
				(xy -3.4798 -1.359916) (xy -2.86004 -1.050036) (xy -3.4798 -0.740156)
			)
			(stroke
				(width 0)
				(type default)
			)
			(fill yes)
			(layer "F.Fab")
		)
		(pad "1" smd rect
			(at -2.175002 -1.050036 180)
			(size 0.6096 1.1684)
			(layers "F.Cu" "F.Mask" "F.Paste")
			(net "P3V3_SSD0")
		)
		(pad "2" smd rect
			(at -2.175002 -0.32512 180)
			(size 0.4318 1.1684)
			(layers "F.Cu" "F.Mask" "F.Paste")
			(net "SMB_ISO_SSD0_SCL")
		)
		(pad "3" smd rect
			(at -2.175002 0.32512 180)
			(size 0.4318 1.1684)
			(layers "F.Cu" "F.Mask" "F.Paste")
			(net "SMB_ISO_SSD0_SDA")
		)
		(pad "4" smd rect
			(at -2.175002 1.050036 180)
			(size 0.6096 1.1684)
			(layers "F.Cu" "F.Mask" "F.Paste")
			(net "GND")
		)
		(pad "5" smd rect
			(at 2.175002 1.050036 180)
			(size 0.6096 1.1684)
			(layers "F.Cu" "F.Mask" "F.Paste")
			(net "SMB_SSD0_ISO_EN")
		)
		(pad "6" smd rect
			(at 2.175002 0.32512 180)
			(size 0.4318 1.1684)
			(layers "F.Cu" "F.Mask" "F.Paste")
			(net "SMB_BIC_I2C9_MUX0_SSD0_R_SDA")
		)
		(pad "7" smd rect
			(at 2.175002 -0.32512 180)
			(size 0.4318 1.1684)
			(layers "F.Cu" "F.Mask" "F.Paste")
			(net "SMB_BIC_I2C9_MUX0_SSD0_R_SCL")
		)
		(pad "8" smd rect
			(at 2.175002 -1.050036 180)
			(size 0.6096 1.1684)
			(layers "F.Cu" "F.Mask" "F.Paste")
			(net "P3V3_AUX")
		)
	)
	(footprint ""
		(layer "F.Cu")
		(at 136.445244 -96.957642)
		(property "Reference" "R1568"
			(at 0 0 0)
			(layer "F.SilkS")
			(hide yes)
			(effects
				(font
					(size 1.27 1.27)
				)
			)
		)
		(property "Value" ""
			(at 0 0 0)
			(layer "F.Fab")
			(effects
				(font
					(size 1.27 1.27)
				)
			)
		)
		(duplicate_pad_numbers_are_jumpers no)
		(fp_line
			(start -0.7874 -0.4064)
			(end 0.7874 -0.4064)
			(stroke
				(width 0.1524)
				(type default)
			)
			(layer "F.SilkS")
		)
		(fp_line
			(start -0.7874 0.4064)
			(end -0.7874 -0.4064)
			(stroke
				(width 0.1524)
				(type default)
			)
			(layer "F.SilkS")
		)
		(fp_line
			(start 0.7874 -0.4064)
			(end 0.7874 0.4064)
			(stroke
				(width 0.1524)
				(type default)
			)
			(layer "F.SilkS")
		)
		(fp_line
			(start 0.7874 0.4064)
			(end -0.7874 0.4064)
			(stroke
				(width 0.1524)
				(type default)
			)
			(layer "F.SilkS")
		)
		(fp_line
			(start -0.67945 -0.305054)
			(end -0.12065 -0.305054)
			(stroke
				(width 0.1)
				(type default)
			)
			(layer "F.Fab")
		)
		(fp_line
			(start -0.67945 0.3048)
			(end -0.67945 -0.305054)
			(stroke
				(width 0.1)
				(type default)
			)
			(layer "F.Fab")
		)
		(fp_line
			(start -0.12065 -0.305054)
			(end -0.12065 -0.2794)
			(stroke
				(width 0.1)
				(type default)
			)
			(layer "F.Fab")
		)
		(fp_line
			(start -0.12065 -0.2794)
			(end 0.12065 -0.2794)
			(stroke
				(width 0.1)
				(type default)
			)
			(layer "F.Fab")
		)
		(fp_line
			(start -0.12065 0.2794)
			(end -0.12065 0.3048)
			(stroke
				(width 0.1)
				(type default)
			)
			(layer "F.Fab")
		)
		(fp_line
			(start -0.12065 0.3048)
			(end -0.67945 0.3048)
			(stroke
				(width 0.1)
				(type default)
			)
			(layer "F.Fab")
		)
		(fp_line
			(start 0.120396 0.2794)
			(end -0.12065 0.2794)
			(stroke
				(width 0.1)
				(type default)
			)
			(layer "F.Fab")
		)
		(fp_line
			(start 0.120396 0.3048)
			(end 0.120396 0.2794)
			(stroke
				(width 0.1)
				(type default)
			)
			(layer "F.Fab")
		)
		(fp_line
			(start 0.12065 -0.3048)
			(end 0.67945 -0.3048)
			(stroke
				(width 0.1)
				(type default)
			)
			(layer "F.Fab")
		)
		(fp_line
			(start 0.12065 -0.2794)
			(end 0.12065 -0.3048)
			(stroke
				(width 0.1)
				(type default)
			)
			(layer "F.Fab")
		)
		(fp_line
			(start 0.67945 -0.3048)
			(end 0.67945 0.3048)
			(stroke
				(width 0.1)
				(type default)
			)
			(layer "F.Fab")
		)
		(fp_line
			(start 0.67945 0.3048)
			(end 0.120396 0.3048)
			(stroke
				(width 0.1)
				(type default)
			)
			(layer "F.Fab")
		)
		(pad "1" smd circle
			(at -0.40005 0)
			(size 0 0)
			(layers "F.Cu" "F.Mask" "F.Paste")
			(net "BIC_I2C9_SSD_MUX0_A2")
		)
		(pad "2" smd circle
			(at 0.40005 0)
			(size 0 0)
			(layers "F.Cu" "F.Mask" "F.Paste")
			(net "GND")
		)
	)
)
